# T6G (Grand Teton) — schematic netlist excerpt (pin names and nets, part order shuffled) for the footprints in the layout excerpt that follows; sources: Cadence DE-HDL packaged netlist, KiCad conversion of 04192023_DAF0TMB3IC0_F0TG_MB_C_brd_V02_OCP.brd

PC620_9  Q_CAP  0.1UF 25V 10% X7R  pkg 0402  page 223 : A = PVDDCR_CPU1_P1_VCCS ; B = GND
C51  Q_CAP_DIFFBUS  DIFF BUS_0.22UF 6.3V 20% X6S  pkg C0201  page 67 : \1\ = P5E_CPU1_P3_TX_C_DP<14> ; \2\ = P5E_CPU1_P3_TX_DP<14>
R231  Q_RES  0 5% CHIP  pkg 0402LF  page 82 : A = PVDDCR_CPU0_P0_OCP_N ; B = FM_PVDDCR_CPU0_P0_OCP_N

(kicad_pcb
	(version 20260206)
	(generator "pcbnew")
	(generator_version "10.0")
	(general
		(thickness 1.6)
		(legacy_teardrops no)
	)
	(paper "A4")
	(title_block
		(title "04192023_DAF0TMB3IC0_F0TG_MB_C_brd_V02_OCP.brd")
		(comment 1 "Grand Teton / footprints 2339-2341 of 8354")
	)
	(layers
		(0 "F.Cu" signal "TOP")
		(4 "In1.Cu" signal "GND")
		(6 "In2.Cu" signal "IN1")
		(8 "In3.Cu" signal "GND1")
		(10 "In4.Cu" signal "IN2")
		(12 "In5.Cu" signal "GND2")
		(14 "In6.Cu" signal "IN3")
		(16 "In7.Cu" signal "GND3")
		(18 "In8.Cu" signal "VCC")
		(20 "In9.Cu" signal "VCC1")
		(22 "In10.Cu" signal "GND4")
		(24 "In11.Cu" signal "IN4")
		(26 "In12.Cu" signal "GND5")
		(28 "In13.Cu" signal "IN5")
		(30 "In14.Cu" signal "GND6")
		(32 "In15.Cu" signal "IN6")
		(34 "In16.Cu" signal "GND7")
		(2 "B.Cu" signal "BOTTOM")
		(9 "F.Adhes" user "F.Adhesive")
		(11 "B.Adhes" user "B.Adhesive")
		(13 "F.Paste" user "Package Geometry/Pastemask Top")
		(15 "B.Paste" user "Package Geometry/Pastemask Bottom")
		(5 "F.SilkS" user "Ref Des/Silkscreen Top")
		(7 "B.SilkS" user "Ref Des/Silkscreen Bottom")
		(1 "F.Mask" user "Board Geometry/Soldermask Top")
		(3 "B.Mask" user "Board Geometry/Soldermask Bottom")
		(17 "Dwgs.User" user "User.Drawings")
		(19 "Cmts.User" user "User.Comments")
		(21 "Eco1.User" user "User.Eco1")
		(23 "Eco2.User" user "User.Eco2")
		(25 "Edge.Cuts" user "Board Geometry/Outline")
		(27 "Margin" user)
		(31 "F.CrtYd" user "Package Geometry/Place Bound Top")
		(29 "B.CrtYd" user "Package Geometry/Place Bound Bottom")
		(35 "F.Fab" user "Ref Des/Assembly Top")
		(33 "B.Fab" user "Ref Des/Assembly Bottom")
	)
	(footprint ""
		(layer "F.Cu")
		(at 181.737 -100.294948 90)
		(property "Reference" "R231"
			(at 0 0 90)
			(layer "F.SilkS")
			(hide yes)
			(effects
				(font
					(size 1.27 1.27)
				)
			)
		)
		(property "Value" ""
			(at 0 0 90)
			(layer "F.Fab")
			(effects
				(font
					(size 1.27 1.27)
				)
			)
		)
		(duplicate_pad_numbers_are_jumpers no)
		(fp_line
			(start 0.7874 -0.4064)
			(end 0.7874 0.4064)
			(stroke
				(width 0.1524)
				(type default)
			)
			(layer "F.SilkS")
		)
		(fp_line
			(start -0.7874 -0.4064)
			(end 0.7874 -0.4064)
			(stroke
				(width 0.1524)
				(type default)
			)
			(layer "F.SilkS")
		)
		(fp_line
			(start 0.7874 0.4064)
			(end -0.7874 0.4064)
			(stroke
				(width 0.1524)
				(type default)
			)
			(layer "F.SilkS")
		)
		(fp_line
			(start -0.7874 0.4064)
			(end -0.7874 -0.4064)
			(stroke
				(width 0.1524)
				(type default)
			)
			(layer "F.SilkS")
		)
		(fp_line
			(start -0.12065 -0.305054)
			(end -0.12065 -0.2794)
			(stroke
				(width 0.1)
				(type default)
			)
			(layer "F.Fab")
		)
		(fp_line
			(start -0.67945 -0.305054)
			(end -0.12065 -0.305054)
			(stroke
				(width 0.1)
				(type default)
			)
			(layer "F.Fab")
		)
		(fp_line
			(start 0.67945 -0.3048)
			(end 0.67945 0.3048)
			(stroke
				(width 0.1)
				(type default)
			)
			(layer "F.Fab")
		)
		(fp_line
			(start 0.12065 -0.3048)
			(end 0.67945 -0.3048)
			(stroke
				(width 0.1)
				(type default)
			)
			(layer "F.Fab")
		)
		(fp_line
			(start 0.12065 -0.2794)
			(end 0.12065 -0.3048)
			(stroke
				(width 0.1)
				(type default)
			)
			(layer "F.Fab")
		)
		(fp_line
			(start -0.12065 -0.2794)
			(end 0.12065 -0.2794)
			(stroke
				(width 0.1)
				(type default)
			)
			(layer "F.Fab")
		)
		(fp_line
			(start 0.120396 0.2794)
			(end -0.12065 0.2794)
			(stroke
				(width 0.1)
				(type default)
			)
			(layer "F.Fab")
		)
		(fp_line
			(start -0.12065 0.2794)
			(end -0.12065 0.3048)
			(stroke
				(width 0.1)
				(type default)
			)
			(layer "F.Fab")
		)
		(fp_line
			(start 0.67945 0.3048)
			(end 0.120396 0.3048)
			(stroke
				(width 0.1)
				(type default)
			)
			(layer "F.Fab")
		)
		(fp_line
			(start 0.120396 0.3048)
			(end 0.120396 0.2794)
			(stroke
				(width 0.1)
				(type default)
			)
			(layer "F.Fab")
		)
		(fp_line
			(start -0.12065 0.3048)
			(end -0.67945 0.3048)
			(stroke
				(width 0.1)
				(type default)
			)
			(layer "F.Fab")
		)
		(fp_line
			(start -0.67945 0.3048)
			(end -0.67945 -0.305054)
			(stroke
				(width 0.1)
				(type default)
			)
			(layer "F.Fab")
		)
		(pad "1" smd circle
			(at -0.40005 0 90)
			(size 0 0)
			(layers "F.Cu" "F.Mask" "F.Paste")
			(net "PVDDCR_CPU0_P0_OCP_N")
		)
		(pad "2" smd circle
			(at 0.40005 0 90)
			(size 0 0)
			(layers "F.Cu" "F.Mask" "F.Paste")
			(net "FM_PVDDCR_CPU0_P0_OCP_N")
		)
	)
	(footprint ""
		(layer "F.Cu")
		(at 34.18713 -351.578672 90)
		(property "Reference" "PC620_9"
			(at 0 0 90)
			(layer "F.SilkS")
			(hide yes)
			(effects
				(font
					(size 1.27 1.27)
				)
			)
		)
		(property "Value" ""
			(at 0 0 90)
			(layer "F.Fab")
			(effects
				(font
					(size 1.27 1.27)
				)
			)
		)
		(duplicate_pad_numbers_are_jumpers no)
		(fp_line
			(start 0.7874 -0.4064)
			(end 0.7874 0.4064)
			(stroke
				(width 0.1524)
				(type default)
			)
			(layer "F.SilkS")
		)
		(fp_line
			(start -0.7874 -0.4064)
			(end 0.7874 -0.4064)
			(stroke
				(width 0.1524)
				(type default)
			)
			(layer "F.SilkS")
		)
		(fp_line
			(start 0.7874 0.4064)
			(end -0.7874 0.4064)
			(stroke
				(width 0.1524)
				(type default)
			)
			(layer "F.SilkS")
		)
		(fp_line
			(start -0.7874 0.4064)
			(end -0.7874 -0.4064)
			(stroke
				(width 0.1524)
				(type default)
			)
			(layer "F.SilkS")
		)
		(fp_line
			(start -0.12065 -0.305054)
			(end -0.12065 -0.2794)
			(stroke
				(width 0.1)
				(type default)
			)
			(layer "F.Fab")
		)
		(fp_line
			(start -0.67945 -0.305054)
			(end -0.12065 -0.305054)
			(stroke
				(width 0.1)
				(type default)
			)
			(layer "F.Fab")
		)
		(fp_line
			(start 0.67945 -0.3048)
			(end 0.67945 0.3048)
			(stroke
				(width 0.1)
				(type default)
			)
			(layer "F.Fab")
		)
		(fp_line
			(start 0.12065 -0.3048)
			(end 0.67945 -0.3048)
			(stroke
				(width 0.1)
				(type default)
			)
			(layer "F.Fab")
		)
		(fp_line
			(start 0.12065 -0.2794)
			(end 0.12065 -0.3048)
			(stroke
				(width 0.1)
				(type default)
			)
			(layer "F.Fab")
		)
		(fp_line
			(start -0.12065 -0.2794)
			(end 0.12065 -0.2794)
			(stroke
				(width 0.1)
				(type default)
			)
			(layer "F.Fab")
		)
		(fp_line
			(start 0.120396 0.2794)
			(end -0.12065 0.2794)
			(stroke
				(width 0.1)
				(type default)
			)
			(layer "F.Fab")
		)
		(fp_line
			(start -0.12065 0.2794)
			(end -0.12065 0.3048)
			(stroke
				(width 0.1)
				(type default)
			)
			(layer "F.Fab")
		)
		(fp_line
			(start 0.67945 0.3048)
			(end 0.120396 0.3048)
			(stroke
				(width 0.1)
				(type default)
			)
			(layer "F.Fab")
		)
		(fp_line
			(start 0.120396 0.3048)
			(end 0.120396 0.2794)
			(stroke
				(width 0.1)
				(type default)
			)
			(layer "F.Fab")
		)
		(fp_line
			(start -0.12065 0.3048)
			(end -0.67945 0.3048)
			(stroke
				(width 0.1)
				(type default)
			)
			(layer "F.Fab")
		)
		(fp_line
			(start -0.67945 0.3048)
			(end -0.67945 -0.305054)
			(stroke
				(width 0.1)
				(type default)
			)
			(layer "F.Fab")
		)
		(pad "1" smd circle
			(at -0.40005 0 90)
			(size 0 0)
			(layers "F.Cu" "F.Mask" "F.Paste")
			(net "PVDDCR_CPU1_P1_VCCS")
		)
		(pad "2" smd circle
			(at 0.40005 0 90)
			(size 0 0)
			(layers "F.Cu" "F.Mask" "F.Paste")
			(net "GND")
		)
	)
	(footprint ""
		(layer "F.Cu")
		(at 136.840976 -376.982228)
		(property "Reference" "C51"
			(at 0 0 0)
			(layer "F.SilkS")
			(hide yes)
			(effects
				(font
					(size 1.27 1.27)
				)
			)
		)
		(property "Value" ""
			(at 0 0 0)
			(layer "F.Fab")
			(effects
				(font
					(size 1.27 1.27)
				)
			)
		)
		(duplicate_pad_numbers_are_jumpers no)
		(fp_line
			(start -0.299974 -0.150114)
			(end 0.299974 -0.150114)
			(stroke
				(width 0.1)
				(type default)
			)
			(layer "F.Fab")
		)
		(fp_line
			(start -0.299974 0.150114)
			(end -0.299974 -0.150114)
			(stroke
				(width 0.1)
				(type default)
			)
			(layer "F.Fab")
		)
		(fp_line
			(start 0.299974 -0.150114)
			(end 0.299974 0.150114)
			(stroke
				(width 0.1)
				(type default)
			)
			(layer "F.Fab")
		)
		(fp_line
			(start 0.299974 0.150114)
			(end -0.299974 0.150114)
			(stroke
				(width 0.1)
				(type default)
			)
			(layer "F.Fab")
		)
		(pad "1" smd rect
			(at -0.2667 0)
			(size 0.3048 0.381)
			(layers "F.Cu" "F.Mask" "F.Paste")
			(net "P5E_CPU1_P3_TX_C_DP<14>")
		)
		(pad "2" smd rect
			(at 0.2667 0)
			(size 0.3048 0.381)
			(layers "F.Cu" "F.Mask" "F.Paste")
			(net "P5E_CPU1_P3_TX_DP<14>")
		)
	)
)
